# T6G (Grand Teton) — schematic netlist excerpt (pin names and nets, part order shuffled) for the footprints in the layout excerpt that follows; sources: Cadence DE-HDL packaged netlist, KiCad conversion of 04192023_DAF0TMB3IC0_F0TG_MB_C_brd_V02_OCP.brd

PC187  Q_CAP  560PF 50V 10% EMPTY  pkg C0402  page 198 : A = SW_PVDDCR_SOC_P0_SW2 ; B = SW_PVDDCR_SOC_P0_SW2_RC
PC195  Q_CAP  560PF 50V 10% EMPTY  pkg C0402  page 216 : A = SW_PVDDCR_SOC_P1_SW3 ; B = SW_PVDDCR_SOC_P1_SW3_RC
C880  Q_CAP_DIFFBUS  DIFF BUS_0.22UF 6.3V 20% X6S  pkg C0201  page 64 : \1\ = P5E_CPU0_P3_TX_C_DN<10> ; \2\ = P5E_CPU0_P3_TX_DN<10>

(kicad_pcb
	(version 20260206)
	(generator "pcbnew")
	(generator_version "10.0")
	(general
		(thickness 1.6)
		(legacy_teardrops no)
	)
	(paper "A4")
	(title_block
		(title "04192023_DAF0TMB3IC0_F0TG_MB_C_brd_V02_OCP.brd")
		(comment 1 "Grand Teton / footprints 359-361 of 8354")
	)
	(layers
		(0 "F.Cu" signal "TOP")
		(4 "In1.Cu" signal "GND")
		(6 "In2.Cu" signal "IN1")
		(8 "In3.Cu" signal "GND1")
		(10 "In4.Cu" signal "IN2")
		(12 "In5.Cu" signal "GND2")
		(14 "In6.Cu" signal "IN3")
		(16 "In7.Cu" signal "GND3")
		(18 "In8.Cu" signal "VCC")
		(20 "In9.Cu" signal "VCC1")
		(22 "In10.Cu" signal "GND4")
		(24 "In11.Cu" signal "IN4")
		(26 "In12.Cu" signal "GND5")
		(28 "In13.Cu" signal "IN5")
		(30 "In14.Cu" signal "GND6")
		(32 "In15.Cu" signal "IN6")
		(34 "In16.Cu" signal "GND7")
		(2 "B.Cu" signal "BOTTOM")
		(9 "F.Adhes" user "F.Adhesive")
		(11 "B.Adhes" user "B.Adhesive")
		(13 "F.Paste" user "Package Geometry/Pastemask Top")
		(15 "B.Paste" user "Package Geometry/Pastemask Bottom")
		(5 "F.SilkS" user "Ref Des/Silkscreen Top")
		(7 "B.SilkS" user "Ref Des/Silkscreen Bottom")
		(1 "F.Mask" user "Board Geometry/Soldermask Top")
		(3 "B.Mask" user "Board Geometry/Soldermask Bottom")
		(17 "Dwgs.User" user "User.Drawings")
		(19 "Cmts.User" user "User.Comments")
		(21 "Eco1.User" user "User.Eco1")
		(23 "Eco2.User" user "User.Eco2")
		(25 "Edge.Cuts" user "Board Geometry/Outline")
		(27 "Margin" user)
		(31 "F.CrtYd" user "Package Geometry/Place Bound Top")
		(29 "B.CrtYd" user "Package Geometry/Place Bound Bottom")
		(35 "F.Fab" user "Ref Des/Assembly Top")
		(33 "B.Fab" user "Ref Des/Assembly Bottom")
	)
	(footprint ""
		(layer "F.Cu")
		(at 409.8417 -171.598082)
		(property "Reference" "PC187"
			(at 0 0 0)
			(layer "F.SilkS")
			(hide yes)
			(effects
				(font
					(size 1.27 1.27)
				)
			)
		)
		(property "Value" ""
			(at 0 0 0)
			(layer "F.Fab")
			(effects
				(font
					(size 1.27 1.27)
				)
			)
		)
		(duplicate_pad_numbers_are_jumpers no)
		(fp_line
			(start -0.7874 -0.4064)
			(end 0.7874 -0.4064)
			(stroke
				(width 0.1524)
				(type default)
			)
			(layer "F.SilkS")
		)
		(fp_line
			(start -0.7874 0.4064)
			(end -0.7874 -0.4064)
			(stroke
				(width 0.1524)
				(type default)
			)
			(layer "F.SilkS")
		)
		(fp_line
			(start 0.7874 -0.4064)
			(end 0.7874 0.4064)
			(stroke
				(width 0.1524)
				(type default)
			)
			(layer "F.SilkS")
		)
		(fp_line
			(start 0.7874 0.4064)
			(end -0.7874 0.4064)
			(stroke
				(width 0.1524)
				(type default)
			)
			(layer "F.SilkS")
		)
		(fp_line
			(start -0.67945 -0.305054)
			(end -0.12065 -0.305054)
			(stroke
				(width 0.1)
				(type default)
			)
			(layer "F.Fab")
		)
		(fp_line
			(start -0.67945 0.3048)
			(end -0.67945 -0.305054)
			(stroke
				(width 0.1)
				(type default)
			)
			(layer "F.Fab")
		)
		(fp_line
			(start -0.12065 -0.305054)
			(end -0.12065 -0.2794)
			(stroke
				(width 0.1)
				(type default)
			)
			(layer "F.Fab")
		)
		(fp_line
			(start -0.12065 -0.2794)
			(end 0.12065 -0.2794)
			(stroke
				(width 0.1)
				(type default)
			)
			(layer "F.Fab")
		)
		(fp_line
			(start -0.12065 0.2794)
			(end -0.12065 0.3048)
			(stroke
				(width 0.1)
				(type default)
			)
			(layer "F.Fab")
		)
		(fp_line
			(start -0.12065 0.3048)
			(end -0.67945 0.3048)
			(stroke
				(width 0.1)
				(type default)
			)
			(layer "F.Fab")
		)
		(fp_line
			(start 0.120396 0.2794)
			(end -0.12065 0.2794)
			(stroke
				(width 0.1)
				(type default)
			)
			(layer "F.Fab")
		)
		(fp_line
			(start 0.120396 0.3048)
			(end 0.120396 0.2794)
			(stroke
				(width 0.1)
				(type default)
			)
			(layer "F.Fab")
		)
		(fp_line
			(start 0.12065 -0.3048)
			(end 0.67945 -0.3048)
			(stroke
				(width 0.1)
				(type default)
			)
			(layer "F.Fab")
		)
		(fp_line
			(start 0.12065 -0.2794)
			(end 0.12065 -0.3048)
			(stroke
				(width 0.1)
				(type default)
			)
			(layer "F.Fab")
		)
		(fp_line
			(start 0.67945 -0.3048)
			(end 0.67945 0.3048)
			(stroke
				(width 0.1)
				(type default)
			)
			(layer "F.Fab")
		)
		(fp_line
			(start 0.67945 0.3048)
			(end 0.120396 0.3048)
			(stroke
				(width 0.1)
				(type default)
			)
			(layer "F.Fab")
		)
		(pad "1" smd circle
			(at -0.40005 0)
			(size 0 0)
			(layers "F.Cu" "F.Mask" "F.Paste")
			(net "SW_PVDDCR_SOC_P0_SW2")
		)
		(pad "2" smd circle
			(at 0.40005 0)
			(size 0 0)
			(layers "F.Cu" "F.Mask" "F.Paste")
			(net "SW_PVDDCR_SOC_P0_SW2_RC")
		)
	)
	(footprint ""
		(layer "F.Cu")
		(at 136.118092 -159.535368)
		(property "Reference" "PC195"
			(at 0 0 0)
			(layer "F.SilkS")
			(hide yes)
			(effects
				(font
					(size 1.27 1.27)
				)
			)
		)
		(property "Value" ""
			(at 0 0 0)
			(layer "F.Fab")
			(effects
				(font
					(size 1.27 1.27)
				)
			)
		)
		(duplicate_pad_numbers_are_jumpers no)
		(fp_line
			(start -0.7874 -0.4064)
			(end 0.7874 -0.4064)
			(stroke
				(width 0.1524)
				(type default)
			)
			(layer "F.SilkS")
		)
		(fp_line
			(start -0.7874 0.4064)
			(end -0.7874 -0.4064)
			(stroke
				(width 0.1524)
				(type default)
			)
			(layer "F.SilkS")
		)
		(fp_line
			(start 0.7874 -0.4064)
			(end 0.7874 0.4064)
			(stroke
				(width 0.1524)
				(type default)
			)
			(layer "F.SilkS")
		)
		(fp_line
			(start 0.7874 0.4064)
			(end -0.7874 0.4064)
			(stroke
				(width 0.1524)
				(type default)
			)
			(layer "F.SilkS")
		)
		(fp_line
			(start -0.67945 -0.305054)
			(end -0.12065 -0.305054)
			(stroke
				(width 0.1)
				(type default)
			)
			(layer "F.Fab")
		)
		(fp_line
			(start -0.67945 0.3048)
			(end -0.67945 -0.305054)
			(stroke
				(width 0.1)
				(type default)
			)
			(layer "F.Fab")
		)
		(fp_line
			(start -0.12065 -0.305054)
			(end -0.12065 -0.2794)
			(stroke
				(width 0.1)
				(type default)
			)
			(layer "F.Fab")
		)
		(fp_line
			(start -0.12065 -0.2794)
			(end 0.12065 -0.2794)
			(stroke
				(width 0.1)
				(type default)
			)
			(layer "F.Fab")
		)
		(fp_line
			(start -0.12065 0.2794)
			(end -0.12065 0.3048)
			(stroke
				(width 0.1)
				(type default)
			)
			(layer "F.Fab")
		)
		(fp_line
			(start -0.12065 0.3048)
			(end -0.67945 0.3048)
			(stroke
				(width 0.1)
				(type default)
			)
			(layer "F.Fab")
		)
		(fp_line
			(start 0.120396 0.2794)
			(end -0.12065 0.2794)
			(stroke
				(width 0.1)
				(type default)
			)
			(layer "F.Fab")
		)
		(fp_line
			(start 0.120396 0.3048)
			(end 0.120396 0.2794)
			(stroke
				(width 0.1)
				(type default)
			)
			(layer "F.Fab")
		)
		(fp_line
			(start 0.12065 -0.3048)
			(end 0.67945 -0.3048)
			(stroke
				(width 0.1)
				(type default)
			)
			(layer "F.Fab")
		)
		(fp_line
			(start 0.12065 -0.2794)
			(end 0.12065 -0.3048)
			(stroke
				(width 0.1)
				(type default)
			)
			(layer "F.Fab")
		)
		(fp_line
			(start 0.67945 -0.3048)
			(end 0.67945 0.3048)
			(stroke
				(width 0.1)
				(type default)
			)
			(layer "F.Fab")
		)
		(fp_line
			(start 0.67945 0.3048)
			(end 0.120396 0.3048)
			(stroke
				(width 0.1)
				(type default)
			)
			(layer "F.Fab")
		)
		(pad "1" smd circle
			(at -0.40005 0)
			(size 0 0)
			(layers "F.Cu" "F.Mask" "F.Paste")
			(net "SW_PVDDCR_SOC_P1_SW3")
		)
		(pad "2" smd circle
			(at 0.40005 0)
			(size 0 0)
			(layers "F.Cu" "F.Mask" "F.Paste")
			(net "SW_PVDDCR_SOC_P1_SW3_RC")
		)
	)
	(footprint ""
		(layer "F.Cu")
		(at 385.723892 -383.88163 -90)
		(property "Reference" "C880"
			(at 0 0 270)
			(layer "F.SilkS")
			(hide yes)
			(effects
				(font
					(size 1.27 1.27)
				)
			)
		)
		(property "Value" ""
			(at 0 0 270)
			(layer "F.Fab")
			(effects
				(font
					(size 1.27 1.27)
				)
			)
		)
		(duplicate_pad_numbers_are_jumpers no)
		(fp_line
			(start -0.299974 0.150114)
			(end -0.299974 -0.150114)
			(stroke
				(width 0.1)
				(type default)
			)
			(layer "F.Fab")
		)
		(fp_line
			(start 0.299974 0.150114)
			(end -0.299974 0.150114)
			(stroke
				(width 0.1)
				(type default)
			)
			(layer "F.Fab")
		)
		(fp_line
			(start -0.299974 -0.150114)
			(end 0.299974 -0.150114)
			(stroke
				(width 0.1)
				(type default)
			)
			(layer "F.Fab")
		)
		(fp_line
			(start 0.299974 -0.150114)
			(end 0.299974 0.150114)
			(stroke
				(width 0.1)
				(type default)
			)
			(layer "F.Fab")
		)
		(pad "1" smd rect
			(at -0.2667 0 270)
			(size 0.3048 0.381)
			(layers "F.Cu" "F.Mask" "F.Paste")
			(net "P5E_CPU0_P3_TX_C_DN<10>")
		)
		(pad "2" smd rect
			(at 0.2667 0 270)
			(size 0.3048 0.381)
			(layers "F.Cu" "F.Mask" "F.Paste")
			(net "P5E_CPU0_P3_TX_DN<10>")
		)
	)
)
